(kicad_pcb
	(version 20241229)
	(generator "pcbnew")
	(generator_version "9.0")
	(general
		(thickness 1.552)
		(legacy_teardrops no)
	)
	(paper "A4")
	(title_block
		(date "2023-07-25")
		(rev "1.1.4")
		(comment 9 "footprints 20-24 of 379")
	)
	(layers
		(0 "F.Cu" signal)
		(4 "In1.Cu" signal)
		(6 "In2.Cu" signal)
		(8 "In3.Cu" signal)
		(10 "In4.Cu" signal)
		(12 "In5.Cu" signal)
		(14 "In6.Cu" signal)
		(2 "B.Cu" signal)
		(9 "F.Adhes" user "F.Adhesive")
		(11 "B.Adhes" user "B.Adhesive")
		(13 "F.Paste" user)
		(15 "B.Paste" user)
		(5 "F.SilkS" user "F.Silkscreen")
		(7 "B.SilkS" user "B.Silkscreen")
		(1 "F.Mask" user)
		(3 "B.Mask" user)
		(17 "Dwgs.User" user "User.Drawings")
		(19 "Cmts.User" user "User.Comments")
		(21 "Eco1.User" user "User.Eco1")
		(23 "Eco2.User" user "User.Eco2")
		(25 "Edge.Cuts" user)
		(27 "Margin" user)
		(31 "F.CrtYd" user "F.Courtyard")
		(29 "B.CrtYd" user "B.Courtyard")
		(35 "F.Fab" user)
		(33 "B.Fab" user)
	)
	(footprint "antmicro-footprints:L_Coilcraft-XEL4030"
		(layer "F.Cu")
		(at 143.08 73.3)
		(property "Reference" "L1"
			(at -3.85 0.14 0)
			(layer "F.SilkS")
			(effects
				(font
					(size 0.65 0.65)
					(thickness 0.15)
				)
				(justify left bottom)
			)
		)
		(property "Value" "L_3u3_5.9A_XEL4030"
			(at 0 3.35 0)
			(layer "F.Fab")
			(hide yes)
			(effects
				(font
					(size 0.7 0.7)
					(thickness 0.15)
				)
				(justify left bottom)
			)
		)
		(property "Datasheet" "https://www.coilcraft.com/getmedia/8245f050-f190-4295-8c41-7c03d662ee3d/xel4030.pdf"
			(at 0 0 0)
			(layer "F.Fab")
			(hide yes)
			(effects
				(font
					(size 1.27 1.27)
					(thickness 0.15)
				)
			)
		)
		(property "Description" "Power Inductor (SMT), AEC-Q200, 3.3 µH, 6.6 A, Shielded, 5.9 A, XEL4030"
			(at 0 0 0)
			(layer "F.Fab")
			(hide yes)
			(effects
				(font
					(size 1.27 1.27)
					(thickness 0.15)
				)
			)
		)
		(property "Author" "Antmicro"
			(at 0 0 0)
			(layer "F.Fab")
			(hide yes)
			(effects
				(font
					(size 1 1)
					(thickness 0.15)
				)
			)
		)
		(property "IMax" "6.6 A"
			(at 0 0 0)
			(layer "F.Fab")
			(hide yes)
			(effects
				(font
					(size 1 1)
					(thickness 0.15)
				)
			)
		)
		(property "ISat" "5.9 A"
			(at 0 0 0)
			(layer "F.Fab")
			(hide yes)
			(effects
				(font
					(size 1 1)
					(thickness 0.15)
				)
			)
		)
		(property "License" "Apache-2.0"
			(at 0 0 0)
			(layer "F.Fab")
			(hide yes)
			(effects
				(font
					(size 1 1)
					(thickness 0.15)
				)
			)
		)
		(property "MPN" "XEL4030-332MEC"
			(at 0 0 0)
			(layer "F.Fab")
			(hide yes)
			(effects
				(font
					(size 1 1)
					(thickness 0.15)
				)
			)
		)
		(property "Manufacturer" "Coilcraft"
			(at 0 0 0)
			(layer "F.Fab")
			(hide yes)
			(effects
				(font
					(size 1 1)
					(thickness 0.15)
				)
			)
		)
		(property "Size" "4.0x4.0"
			(at 0 0 0)
			(layer "F.Fab")
			(hide yes)
			(effects
				(font
					(size 1 1)
					(thickness 0.15)
				)
			)
		)
		(property "Val" "3u3/6.6A"
			(at 0 0 0)
			(layer "F.Fab")
			(hide yes)
			(effects
				(font
					(size 1 1)
					(thickness 0.15)
				)
			)
		)
		(sheetname "/Power Supply/")
		(sheetfile "supply.kicad_sch")
		(attr smd)
		(fp_line
			(start -2.2 -2.2)
			(end 2.2 -2.2)
			(stroke
				(width 0.15)
				(type solid)
			)
			(layer "F.SilkS")
		)
		(fp_line
			(start -2.2 2.2)
			(end -2.2 -2.2)
			(stroke
				(width 0.15)
				(type solid)
			)
			(layer "F.SilkS")
		)
		(fp_line
			(start -2.2 2.2)
			(end 2.2 2.2)
			(stroke
				(width 0.15)
				(type solid)
			)
			(layer "F.SilkS")
		)
		(fp_line
			(start 2.2 2.2)
			(end 2.2 -2.2)
			(stroke
				(width 0.15)
				(type solid)
			)
			(layer "F.SilkS")
		)
		(fp_rect
			(start -2.4 -2.4)
			(end 2.4 2.4)
			(stroke
				(width 0.05)
				(type solid)
			)
			(fill no)
			(layer "F.CrtYd")
		)
		(fp_rect
			(start -2.15 -2.15)
			(end 2.15 2.15)
			(stroke
				(width 0.15)
				(type solid)
			)
			(fill no)
			(layer "F.Fab")
		)
		(fp_text user "${REFERENCE}"
			(at -2.4 6.55 0)
			(layer "F.Fab")
			(effects
				(font
					(size 0.7 0.7)
					(thickness 0.15)
				)
				(justify left bottom)
			)
		)
		(fp_text user "License: Apache-2.0"
			(at -2.4 7.75 0)
			(layer "F.Fab")
			(effects
				(font
					(size 0.7 0.7)
					(thickness 0.15)
				)
				(justify left bottom)
			)
		)
		(fp_text user "Author: Antmicro"
			(at -2.4 5.35 0)
			(layer "F.Fab")
			(effects
				(font
					(size 0.7 0.7)
					(thickness 0.15)
				)
				(justify left bottom)
			)
		)
		(pad "1" smd roundrect
			(at -1.185 0)
			(size 0.98 3.4)
			(layers "F.Cu" "F.Mask" "F.Paste")
			(roundrect_rratio 0.1)
			(net 276 "/Power Supply/1V0_SW")
			(pintype "passive")
		)
		(pad "2" smd roundrect
			(at 1.185 0)
			(size 0.98 3.4)
			(layers "F.Cu" "F.Mask" "F.Paste")
			(roundrect_rratio 0.1)
			(net 273 "/Power Supply/1V0_OUT")
			(pintype "passive")
		)
	)
	(footprint "antmicro-footprints:C_0603_1608Metric"
		(layer "F.Cu")
		(at 140.84 64.8 90)
		(descr "Capacitor SMD 0603")
		(tags "capacitor 0603")
		(property "Reference" "C33"
			(at -0.84 -5.01 90)
			(layer "F.SilkS")
			(effects
				(font
					(size 0.65 0.65)
					(thickness 0.15)
				)
				(justify left bottom)
			)
		)
		(property "Value" "C_22u_0603"
			(at 0 1.6 90)
			(layer "F.Fab")
			(hide yes)
			(effects
				(font
					(size 0.7 0.7)
					(thickness 0.15)
				)
				(justify left bottom)
			)
		)
		(property "Datasheet" "https://www.murata.com/products/productdetail?partno=GRM188R60J226MEA0%23"
			(at 0 0 90)
			(layer "F.Fab")
			(hide yes)
			(effects
				(font
					(size 1.27 1.27)
					(thickness 0.15)
				)
			)
		)
		(property "Description" "SMD Multilayer Ceramic Capacitor, 22 µF, 6.3 V, 0603 [1608 Metric], ± 20%, X5R, GRM Series"
			(at 0 0 90)
			(layer "F.Fab")
			(hide yes)
			(effects
				(font
					(size 1.27 1.27)
					(thickness 0.15)
				)
			)
		)
		(property "Author" "Antmicro"
			(at 205.64 -76.04 0)
			(layer "F.Fab")
			(hide yes)
			(effects
				(font
					(size 1 1)
					(thickness 0.15)
				)
			)
		)
		(property "Dielectric" ""
			(at 205.64 -76.04 0)
			(layer "F.Fab")
			(hide yes)
			(effects
				(font
					(size 1 1)
					(thickness 0.15)
				)
			)
		)
		(property "License" "Apache-2.0"
			(at 205.64 -76.04 0)
			(layer "F.Fab")
			(hide yes)
			(effects
				(font
					(size 1 1)
					(thickness 0.15)
				)
			)
		)
		(property "MPN" "GRM188R60J226MEA0D"
			(at 205.64 -76.04 0)
			(layer "F.Fab")
			(hide yes)
			(effects
				(font
					(size 1 1)
					(thickness 0.15)
				)
			)
		)
		(property "Manufacturer" "Murata"
			(at 205.64 -76.04 0)
			(layer "F.Fab")
			(hide yes)
			(effects
				(font
					(size 1 1)
					(thickness 0.15)
				)
			)
		)
		(property "Val" "22u"
			(at 205.64 -76.04 0)
			(layer "F.Fab")
			(hide yes)
			(effects
				(font
					(size 1 1)
					(thickness 0.15)
				)
			)
		)
		(property "Voltage" ""
			(at 205.64 -76.04 0)
			(layer "F.Fab")
			(hide yes)
			(effects
				(font
					(size 1 1)
					(thickness 0.15)
				)
			)
		)
		(sheetname "/Power Supply/")
		(sheetfile "supply.kicad_sch")
		(attr smd)
		(fp_line
			(start -0.15 -0.4)
			(end 0.15 -0.4)
			(stroke
				(width 0.15)
				(type solid)
			)
			(layer "F.SilkS")
		)
		(fp_line
			(start -0.15 0.4)
			(end 0.15 0.4)
			(stroke
				(width 0.15)
				(type solid)
			)
			(layer "F.SilkS")
		)
		(fp_rect
			(start -1.25 -0.65)
			(end 1.25 0.65)
			(stroke
				(width 0.05)
				(type solid)
			)
			(fill no)
			(layer "F.CrtYd")
		)
		(fp_rect
			(start -0.8 -0.4)
			(end 0.8 0.4)
			(stroke
				(width 0.15)
				(type solid)
			)
			(fill no)
			(layer "F.Fab")
		)
		(fp_text user "License: Apache-2.0"
			(at -1.682 5.895 90)
			(layer "F.Fab")
			(effects
				(font
					(size 0.7 0.7)
					(thickness 0.15)
				)
				(justify left bottom)
			)
		)
		(fp_text user "Author: Antmicro"
			(at -1.682 4.894 90)
			(layer "F.Fab")
			(effects
				(font
					(size 0.7 0.7)
					(thickness 0.15)
				)
				(justify left bottom)
			)
		)
		(fp_text user "${REFERENCE}"
			(at -1.682 3.895 90)
			(layer "F.Fab")
			(effects
				(font
					(size 0.7 0.7)
					(thickness 0.15)
				)
				(justify left bottom)
			)
		)
		(pad "1" smd roundrect
			(at -0.7 0 90)
			(size 0.8 1)
			(layers "F.Cu" "F.Mask" "F.Paste")
			(roundrect_rratio 0.2)
			(net 1 "GND")
			(pintype "passive")
		)
		(pad "2" smd roundrect
			(at 0.7 0 90)
			(size 0.8 1)
			(layers "F.Cu" "F.Mask" "F.Paste")
			(roundrect_rratio 0.2)
			(net 274 "/Power Supply/1V5_OUT")
			(pintype "passive")
		)
	)
	(footprint "antmicro-footprints:R_0603_1608Metric"
		(layer "F.Cu")
		(at 164.29 76.6)
		(descr "Resistor SMD 0603")
		(tags "resistor SMD 0603")
		(property "Reference" "R118"
			(at -1.26 -0.76 0)
			(layer "F.SilkS")
			(effects
				(font
					(size 0.65 0.65)
					(thickness 0.15)
				)
				(justify left bottom)
			)
		)
		(property "Value" "R_15k_0603"
			(at 0 1.6 0)
			(layer "F.Fab")
			(hide yes)
			(effects
				(font
					(size 0.7 0.7)
					(thickness 0.15)
				)
				(justify left bottom)
			)
		)
		(property "Datasheet" "https://www.bourns.com/docs/product-datasheets/cr.pdf"
			(at 0 0 0)
			(layer "F.Fab")
			(hide yes)
			(effects
				(font
					(size 1.27 1.27)
					(thickness 0.15)
				)
			)
		)
		(property "Description" "SMD Chip Resistor, 15 kohm, ± 1%, 100 mW, 0603 [1608 Metric], Thick Film, General Purpose"
			(at 0 0 0)
			(layer "F.Fab")
			(hide yes)
			(effects
				(font
					(size 1.27 1.27)
					(thickness 0.15)
				)
			)
		)
		(property "Author" "Antmicro"
			(at 0 0 0)
			(layer "F.Fab")
			(hide yes)
			(effects
				(font
					(size 1 1)
					(thickness 0.15)
				)
			)
		)
		(property "License" "Apache-2.0"
			(at 0 0 0)
			(layer "F.Fab")
			(hide yes)
			(effects
				(font
					(size 1 1)
					(thickness 0.15)
				)
			)
		)
		(property "MPN" "CR0603-FX-1502ELF"
			(at 0 0 0)
			(layer "F.Fab")
			(hide yes)
			(effects
				(font
					(size 1 1)
					(thickness 0.15)
				)
			)
		)
		(property "Manufacturer" "Bourns"
			(at 0 0 0)
			(layer "F.Fab")
			(hide yes)
			(effects
				(font
					(size 1 1)
					(thickness 0.15)
				)
			)
		)
		(property "Tolerance" "1%"
			(at 0 0 0)
			(layer "F.Fab")
			(hide yes)
			(effects
				(font
					(size 1 1)
					(thickness 0.15)
				)
			)
		)
		(property "Val" "15k"
			(at 0 0 0)
			(layer "F.Fab")
			(hide yes)
			(effects
				(font
					(size 1 1)
					(thickness 0.15)
				)
			)
		)
		(sheetname "/Peripherals/")
		(sheetfile "peripherals.kicad_sch")
		(attr smd)
		(fp_line
			(start -0.15 -0.4)
			(end 0.15 -0.4)
			(stroke
				(width 0.15)
				(type solid)
			)
			(layer "F.SilkS")
		)
		(fp_line
			(start -0.15 0.4)
			(end 0.15 0.4)
			(stroke
				(width 0.15)
				(type solid)
			)
			(layer "F.SilkS")
		)
		(fp_rect
			(start -1.25 -0.65)
			(end 1.25 0.65)
			(stroke
				(width 0.05)
				(type solid)
			)
			(fill no)
			(layer "F.CrtYd")
		)
		(fp_rect
			(start -0.8 -0.4)
			(end 0.8 0.4)
			(stroke
				(width 0.15)
				(type solid)
			)
			(fill no)
			(layer "F.Fab")
		)
		(fp_text user "${REFERENCE}"
			(at -1.25 3.898 0)
			(layer "F.Fab")
			(effects
				(font
					(size 0.7 0.7)
					(thickness 0.15)
				)
				(justify left bottom)
			)
		)
		(fp_text user "Author: Antmicro"
			(at -1.25 4.9 0)
			(layer "F.Fab")
			(effects
				(font
					(size 0.7 0.7)
					(thickness 0.15)
				)
				(justify left bottom)
			)
		)
		(fp_text user "License: Apache-2.0"
			(at -1.25 5.9 0)
			(layer "F.Fab")
			(effects
				(font
					(size 0.7 0.7)
					(thickness 0.15)
				)
				(justify left bottom)
			)
		)
		(pad "1" smd roundrect
			(at -0.7 0)
			(size 0.8 1)
			(layers "F.Cu" "F.Mask" "F.Paste")
			(roundrect_rratio 0.2)
			(net 1 "GND")
			(pintype "passive")
		)
		(pad "2" smd roundrect
			(at 0.7 0)
			(size 0.8 1)
			(layers "F.Cu" "F.Mask" "F.Paste")
			(roundrect_rratio 0.2)
			(net 356 "Net-(U19-ILIM)")
			(pintype "passive")
		)
	)
	(footprint "antmicro-footprints:TP_SMD_0.75mm"
		(layer "F.Cu")
		(at 136.29 114.3 90)
		(property "Reference" "TP8"
			(at -2.64 0.34 90)
			(layer "F.SilkS")
			(effects
				(font
					(size 0.65 0.65)
					(thickness 0.15)
				)
				(justify left bottom)
			)
		)
		(property "Value" "TP_0.75mm_SMD"
			(at 0 1.2 90)
			(layer "F.Fab")
			(hide yes)
			(effects
				(font
					(size 0.7 0.7)
					(thickness 0.15)
				)
				(justify left bottom)
			)
		)
		(property "Description" "SMT test point"
			(at 0 0 90)
			(layer "F.Fab")
			(hide yes)
			(effects
				(font
					(size 1.27 1.27)
					(thickness 0.15)
				)
			)
		)
		(property "Author" "Antmicro"
			(at 250.59 -21.99 0)
			(layer "F.Fab")
			(hide yes)
			(effects
				(font
					(size 1 1)
					(thickness 0.15)
				)
			)
		)
		(property "License" "Apache-2.0"
			(at 250.59 -21.99 0)
			(layer "F.Fab")
			(hide yes)
			(effects
				(font
					(size 1 1)
					(thickness 0.15)
				)
			)
		)
		(property "MPN" ""
			(at 250.59 -21.99 0)
			(layer "F.Fab")
			(hide yes)
			(effects
				(font
					(size 1 1)
					(thickness 0.15)
				)
			)
		)
		(property "Manufacturer" ""
			(at 250.59 -21.99 0)
			(layer "F.Fab")
			(hide yes)
			(effects
				(font
					(size 1 1)
					(thickness 0.15)
				)
			)
		)
		(sheetname "/Power Supply/")
		(sheetfile "supply.kicad_sch")
		(attr exclude_from_pos_files)
		(fp_circle
			(center 0 0)
			(end 0.475 0)
			(stroke
				(width 0.05)
				(type default)
			)
			(fill no)
			(layer "F.CrtYd")
		)
		(fp_text user "License: Apache-2.0"
			(at -0.4 5.101 90)
			(layer "F.Fab")
			(effects
				(font
					(size 0.7 0.7)
					(thickness 0.15)
				)
				(justify left bottom)
			)
		)
		(fp_text user "Author: Antmicro"
			(at -0.4 3.901 90)
			(layer "F.Fab")
			(effects
				(font
					(size 0.7 0.7)
					(thickness 0.15)
				)
				(justify left bottom)
			)
		)
		(fp_text user "${REFERENCE}"
			(at -0.4 2.7 90)
			(layer "F.Fab")
			(effects
				(font
					(size 0.7 0.7)
					(thickness 0.15)
				)
				(justify left bottom)
			)
		)
		(pad "1" smd circle
			(at 0 0 90)
			(size 0.75 0.75)
			(layers "F.Cu" "F.Mask")
			(net 3 "+1V2")
			(pinfunction "1")
			(pintype "passive")
		)
	)
	(footprint "antmicro-footprints:R_0402_1005Metric"
		(layer "F.Cu")
		(at 145.84 114.95 90)
		(descr "Resistor SMD 0402")
		(tags "resistor SMD 0402")
		(property "Reference" "R25"
			(at -0.99 2.79 270)
			(layer "F.SilkS")
			(effects
				(font
					(size 0.65 0.65)
					(thickness 0.15)
				)
				(justify left bottom)
			)
		)
		(property "Value" "R_0R_0402"
			(at 0 1.4 90)
			(layer "F.Fab")
			(hide yes)
			(effects
				(font
					(size 0.7 0.7)
					(thickness 0.15)
				)
				(justify left bottom)
			)
		)
		(property "Datasheet" "https://industrial.panasonic.com/cdbs/www-data/pdf/RDA0000/AOA0000C301.pdf"
			(at 0 0 90)
			(layer "F.Fab")
			(hide yes)
			(effects
				(font
					(size 1.27 1.27)
					(thickness 0.15)
				)
			)
		)
		(property "Description" "SMD Chip Resistor, Jumper, 0 ohm, 100 mW, 0402 [1005 Metric], Thick Film, General Purpose"
			(at 0 0 90)
			(layer "F.Fab")
			(hide yes)
			(effects
				(font
					(size 1.27 1.27)
					(thickness 0.15)
				)
			)
		)
		(property "Author" "Antmicro"
			(at 260.79 -30.89 0)
			(layer "F.Fab")
			(hide yes)
			(effects
				(font
					(size 1 1)
					(thickness 0.15)
				)
			)
		)
		(property "Current" "1A"
			(at 260.79 -30.89 0)
			(layer "F.Fab")
			(hide yes)
			(effects
				(font
					(size 1 1)
					(thickness 0.15)
				)
			)
		)
		(property "License" "Apache-2.0"
			(at 260.79 -30.89 0)
			(layer "F.Fab")
			(hide yes)
			(effects
				(font
					(size 1 1)
					(thickness 0.15)
				)
			)
		)
		(property "MPN" "ERJ2GE0R00X"
			(at 260.79 -30.89 0)
			(layer "F.Fab")
			(hide yes)
			(effects
				(font
					(size 1 1)
					(thickness 0.15)
				)
			)
		)
		(property "Manufacturer" "Panasonic"
			(at 260.79 -30.89 0)
			(layer "F.Fab")
			(hide yes)
			(effects
				(font
					(size 1 1)
					(thickness 0.15)
				)
			)
		)
		(property "Tolerance" "~"
			(at 260.79 -30.89 0)
			(layer "F.Fab")
			(hide yes)
			(effects
				(font
					(size 1 1)
					(thickness 0.15)
				)
			)
		)
		(property "Val" "0R"
			(at 260.79 -30.89 0)
			(layer "F.Fab")
			(hide yes)
			(effects
				(font
					(size 1 1)
					(thickness 0.15)
				)
			)
		)
		(sheetname "/Power Supply/")
		(sheetfile "supply.kicad_sch")
		(attr smd)
		(fp_rect
			(start -0.925 -0.47)
			(end 0.925 0.47)
			(stroke
				(width 0.05)
				(type default)
			)
			(fill no)
			(layer "F.CrtYd")
		)
		(fp_rect
			(start -0.5 -0.25)
			(end 0.5 0.25)
			(stroke
				(width 0.15)
				(type solid)
			)
			(fill no)
			(layer "F.Fab")
		)
		(fp_text user "${REFERENCE}"
			(at -0.95 3.168 90)
			(layer "F.Fab")
			(effects
				(font
					(size 0.7 0.7)
					(thickness 0.15)
				)
				(justify left bottom)
			)
		)
		(fp_text user "License: Apache-2.0"
			(at -0.95 5.169 90)
			(layer "F.Fab")
			(effects
				(font
					(size 0.7 0.7)
					(thickness 0.15)
				)
				(justify left bottom)
			)
		)
		(fp_text user "Author: Antmicro"
			(at -0.95 4.169 90)
			(layer "F.Fab")
			(effects
				(font
					(size 0.7 0.7)
					(thickness 0.15)
				)
				(justify left bottom)
			)
		)
		(pad "1" smd roundrect
			(at -0.48 0 90)
			(size 0.59 0.64)
			(layers "F.Cu" "F.Mask" "F.Paste")
			(roundrect_rratio 0.25)
			(net 265 "Net-(U9-V_{IN})")
			(pintype "passive")
		)
		(pad "2" smd roundrect
			(at 0.48 0 90)
			(size 0.59 0.64)
			(layers "F.Cu" "F.Mask" "F.Paste")
			(roundrect_rratio 0.25)
			(net 269 "Net-(U9-EN)")
			(pintype "passive")
		)
	)
)
